(kicad_pcb
	(version 20241229)
	(generator "pcbnew")
	(generator_version "9.0")
	(general
		(thickness 1.294)
		(legacy_teardrops no)
	)
	(paper "A3")
	(title_block
		(title "Kintex 410T devboard")
		(date "2024-04-03")
		(rev "1.1.2")
		(comment 9 "footprints 685-690 of 975")
	)
	(layers
		(0 "F.Cu" mixed)
		(4 "In1.Cu" power)
		(6 "In2.Cu" power)
		(8 "In3.Cu" mixed)
		(10 "In4.Cu" power)
		(12 "In5.Cu" mixed)
		(14 "In6.Cu" power)
		(16 "In7.Cu" mixed)
		(18 "In8.Cu" power)
		(2 "B.Cu" mixed)
		(9 "F.Adhes" user "F.Adhesive")
		(11 "B.Adhes" user "B.Adhesive")
		(13 "F.Paste" user)
		(15 "B.Paste" user)
		(5 "F.SilkS" user "F.Silkscreen")
		(7 "B.SilkS" user "B.Silkscreen")
		(1 "F.Mask" user)
		(3 "B.Mask" user)
		(17 "Dwgs.User" user "User.Drawings")
		(19 "Cmts.User" user "User.Comments")
		(21 "Eco1.User" user "User.Eco1")
		(23 "Eco2.User" user "User.Eco2")
		(25 "Edge.Cuts" user)
		(27 "Margin" user)
		(31 "F.CrtYd" user "F.Courtyard")
		(29 "B.CrtYd" user "B.Courtyard")
		(35 "F.Fab" user)
		(33 "B.Fab" user)
	)
	(footprint "antmicro-footprints:R_Array_4x0201_Panasonic_EXB18V"
		(layer "B.Cu")
		(at 247.901 149.15)
		(property "Reference" "R29"
			(at 1.074 1.475 0)
			(layer "B.SilkS")
			(effects
				(font
					(size 0.7 0.7)
					(thickness 0.15)
				)
				(justify left bottom mirror)
			)
		)
		(property "Value" "R_4x33R_0201_array"
			(at -1.1 -1.8 0)
			(layer "B.Fab")
			(effects
				(font
					(size 0.7 0.7)
					(thickness 0.15)
				)
				(justify right bottom mirror)
			)
		)
		(property "Description" "Fixed Network Resistor, 33 ohm, Isolated, 4 Resistors, 0502 [1406 Metric], Flat, ± 5%"
			(at 0 0 0)
			(layer "F.Fab")
			(hide yes)
			(effects
				(font
					(size 1.27 1.27)
					(thickness 0.15)
				)
			)
		)
		(property "Author" "Antmicro"
			(at 0 0 0)
			(layer "B.Fab")
			(hide yes)
			(effects
				(font
					(size 1 1)
					(thickness 0.15)
				)
				(justify mirror)
			)
		)
		(property "License" "Apache-2.0"
			(at 0 0 0)
			(layer "B.Fab")
			(hide yes)
			(effects
				(font
					(size 1 1)
					(thickness 0.15)
				)
				(justify mirror)
			)
		)
		(property "MPN" "EXB-18V330JX"
			(at 0 0 0)
			(layer "B.Fab")
			(hide yes)
			(effects
				(font
					(size 1 1)
					(thickness 0.15)
				)
				(justify mirror)
			)
		)
		(property "Manufacturer" "Panasonic"
			(at 0 0 0)
			(layer "B.Fab")
			(hide yes)
			(effects
				(font
					(size 1 1)
					(thickness 0.15)
				)
				(justify mirror)
			)
		)
		(property "Val" "R_4x33R_0201"
			(at 0 0 0)
			(layer "B.Fab")
			(hide yes)
			(effects
				(font
					(size 1 1)
					(thickness 0.15)
				)
				(justify mirror)
			)
		)
		(sheetname "Supervisior MCU")
		(sheetfile "supervisor-mcu.kicad_sch")
		(attr smd)
		(fp_line
			(start -0.8 0.45)
			(end -0.8 -0.45)
			(stroke
				(width 0.12)
				(type solid)
			)
			(layer "B.SilkS")
		)
		(fp_line
			(start 0.8 0.45)
			(end 0.8 -0.45)
			(stroke
				(width 0.12)
				(type solid)
			)
			(layer "B.SilkS")
		)
		(fp_rect
			(start -0.898 0.66)
			(end 0.898 -0.65)
			(stroke
				(width 0.05)
				(type solid)
			)
			(fill no)
			(layer "B.CrtYd")
		)
		(pad "1" smd roundrect
			(at -0.6 -0.298)
			(size 0.2 0.4)
			(layers "B.Cu" "B.Mask" "B.Paste")
			(roundrect_rratio 0.25)
			(net 1374 "/SUP_MCU.D6")
			(pinfunction "R1.1")
			(pintype "passive")
		)
		(pad "2" smd roundrect
			(at -0.202 -0.298)
			(size 0.2 0.4)
			(layers "B.Cu" "B.Mask" "B.Paste")
			(roundrect_rratio 0.25)
			(net 1375 "/SUP_MCU.D7")
			(pinfunction "R2.1")
			(pintype "passive")
		)
		(pad "3" smd roundrect
			(at 0.2 -0.298)
			(size 0.2 0.4)
			(layers "B.Cu" "B.Mask" "B.Paste")
			(roundrect_rratio 0.25)
			(net 1376 "/SUP_MCU.CE")
			(pinfunction "R3.1")
			(pintype "passive")
		)
		(pad "4" smd roundrect
			(at 0.598 -0.298)
			(size 0.2 0.4)
			(layers "B.Cu" "B.Mask" "B.Paste")
			(roundrect_rratio 0.25)
			(net 1316 "/SUP_MCU.INITB")
			(pinfunction "R4.1")
			(pintype "passive")
		)
		(pad "5" smd roundrect
			(at 0.598 0.3)
			(size 0.2 0.4)
			(layers "B.Cu" "B.Mask" "B.Paste")
			(roundrect_rratio 0.25)
			(net 1060 "/Supervisior MCU/CFG_INITB")
			(pinfunction "R4.2")
			(pintype "passive")
		)
		(pad "6" smd roundrect
			(at 0.2 0.3)
			(size 0.2 0.4)
			(layers "B.Cu" "B.Mask" "B.Paste")
			(roundrect_rratio 0.25)
			(net 1095 "/Supervisior MCU/USB_CE")
			(pinfunction "R3.2")
			(pintype "passive")
		)
		(pad "7" smd roundrect
			(at -0.202 0.3)
			(size 0.2 0.4)
			(layers "B.Cu" "B.Mask" "B.Paste")
			(roundrect_rratio 0.25)
			(net 1113 "/Supervisior MCU/USB_D7")
			(pinfunction "R2.2")
			(pintype "passive")
		)
		(pad "8" smd roundrect
			(at -0.6 0.3)
			(size 0.2 0.4)
			(layers "B.Cu" "B.Mask" "B.Paste")
			(roundrect_rratio 0.25)
			(net 1112 "/Supervisior MCU/USB_D6")
			(pinfunction "R1.2")
			(pintype "passive")
		)
	)
	(footprint "antmicro-footprints:SOD-523"
		(layer "B.Cu")
		(at 237.426 137.7)
		(property "Reference" "D38"
			(at -0.951 0.375 180)
			(layer "B.SilkS")
			(effects
				(font
					(size 0.7 0.7)
					(thickness 0.15)
				)
				(justify left bottom mirror)
			)
		)
		(property "Value" "BAT54-02V-G3-08"
			(at 0 -1.499 180)
			(layer "B.Fab")
			(effects
				(font
					(size 0.7 0.7)
					(thickness 0.15)
				)
				(justify left bottom mirror)
			)
		)
		(property "Description" "Small Signal Schottky Diode, Single, 30 V, 200 mA, 800 mV, 600 mA, 125 °C"
			(at 0 0 0)
			(layer "F.Fab")
			(hide yes)
			(effects
				(font
					(size 1.27 1.27)
					(thickness 0.15)
				)
			)
		)
		(property "Author" "Antmicro"
			(at 0 0 0)
			(layer "B.Fab")
			(hide yes)
			(effects
				(font
					(size 1 1)
					(thickness 0.15)
				)
				(justify mirror)
			)
		)
		(property "License" "Apache-2.0"
			(at 0 0 0)
			(layer "B.Fab")
			(hide yes)
			(effects
				(font
					(size 1 1)
					(thickness 0.15)
				)
				(justify mirror)
			)
		)
		(property "MPN" "BAT54-02V-G3-08"
			(at 0 0 0)
			(layer "B.Fab")
			(hide yes)
			(effects
				(font
					(size 1 1)
					(thickness 0.15)
				)
				(justify mirror)
			)
		)
		(property "Manufacturer" "Vishay"
			(at 0 0 0)
			(layer "B.Fab")
			(hide yes)
			(effects
				(font
					(size 1 1)
					(thickness 0.15)
				)
				(justify mirror)
			)
		)
		(property "Public" "False"
			(at 0 0 0)
			(layer "B.Fab")
			(hide yes)
			(effects
				(font
					(size 1 1)
					(thickness 0.15)
				)
				(justify mirror)
			)
		)
		(sheetname "USB PHY")
		(sheetfile "usb-phy.kicad_sch")
		(attr smd)
		(fp_line
			(start -0.35 0.5)
			(end -0.35 -0.5)
			(stroke
				(width 0.15)
				(type solid)
			)
			(layer "B.SilkS")
		)
		(fp_rect
			(start -1 0.6)
			(end 1 -0.6)
			(stroke
				(width 0.05)
				(type solid)
			)
			(fill no)
			(layer "B.CrtYd")
		)
		(fp_line
			(start -0.652 -0.423)
			(end -0.652 0.425)
			(stroke
				(width 0.15)
				(type solid)
			)
			(layer "B.Fab")
		)
		(fp_line
			(start -0.652 -0.423)
			(end 0.65 -0.423)
			(stroke
				(width 0.15)
				(type solid)
			)
			(layer "B.Fab")
		)
		(fp_line
			(start -0.652 0.425)
			(end 0.65 0.425)
			(stroke
				(width 0.15)
				(type solid)
			)
			(layer "B.Fab")
		)
		(fp_line
			(start -0.35 0.4)
			(end -0.35 -0.4)
			(stroke
				(width 0.15)
				(type solid)
			)
			(layer "B.Fab")
		)
		(fp_line
			(start 0.65 0.425)
			(end 0.65 -0.423)
			(stroke
				(width 0.15)
				(type solid)
			)
			(layer "B.Fab")
		)
		(pad "1" smd roundrect
			(at -0.701 0)
			(size 0.5 0.6)
			(layers "B.Cu" "B.Mask" "B.Paste")
			(roundrect_rratio 0.25)
			(net 1205 "Net-(D38-Pad1)")
			(pinfunction "C")
			(pintype "passive")
		)
		(pad "2" smd roundrect
			(at 0.699 0)
			(size 0.5 0.6)
			(layers "B.Cu" "B.Mask" "B.Paste")
			(roundrect_rratio 0.25)
			(net 24 "+3V3")
			(pinfunction "A")
			(pintype "passive")
		)
	)
	(footprint "antmicro-footprints:R_0402_1005Metric"
		(layer "B.Cu")
		(at 198.491252 94.55)
		(descr "Resistor SMD 0402")
		(tags "resistor SMD 0402")
		(property "Reference" "R212"
			(at 1.483748 -4.6 180)
			(layer "B.SilkS")
			(effects
				(font
					(size 0.7 0.7)
					(thickness 0.15)
				)
				(justify left bottom mirror)
			)
		)
		(property "Value" "R_2k2_0402"
			(at 0 -1.4 180)
			(layer "B.Fab")
			(effects
				(font
					(size 0.7 0.7)
					(thickness 0.15)
				)
				(justify left bottom mirror)
			)
		)
		(property "Description" "SMD Chip Resistor, 2.2 kohm, ± 1%, 62.5 mW, 0402 [1005 Metric], Thick Film, General Purpose"
			(at 0 0 0)
			(layer "F.Fab")
			(hide yes)
			(effects
				(font
					(size 1.27 1.27)
					(thickness 0.15)
				)
			)
		)
		(property "Author" "Antmicro"
			(at 0 0 0)
			(layer "B.Fab")
			(hide yes)
			(effects
				(font
					(size 1 1)
					(thickness 0.15)
				)
				(justify mirror)
			)
		)
		(property "License" "Apache-2.0"
			(at 0 0 0)
			(layer "B.Fab")
			(hide yes)
			(effects
				(font
					(size 1 1)
					(thickness 0.15)
				)
				(justify mirror)
			)
		)
		(property "MPN" "CR0402-FX-2201GLF"
			(at 0 0 0)
			(layer "B.Fab")
			(hide yes)
			(effects
				(font
					(size 1 1)
					(thickness 0.15)
				)
				(justify mirror)
			)
		)
		(property "Manufacturer" "Bourns"
			(at 0 0 0)
			(layer "B.Fab")
			(hide yes)
			(effects
				(font
					(size 1 1)
					(thickness 0.15)
				)
				(justify mirror)
			)
		)
		(property "Tolerance" "1%"
			(at 0 0 0)
			(layer "B.Fab")
			(hide yes)
			(effects
				(font
					(size 1 1)
					(thickness 0.15)
				)
				(justify mirror)
			)
		)
		(property "Val" "2k2"
			(at 0 0 0)
			(layer "B.Fab")
			(hide yes)
			(effects
				(font
					(size 1 1)
					(thickness 0.15)
				)
				(justify mirror)
			)
		)
		(sheetname "HDMI + Ethernet")
		(sheetfile "hdmi-ethernet.kicad_sch")
		(attr smd)
		(fp_rect
			(start -0.925 0.47)
			(end 0.925 -0.47)
			(stroke
				(width 0.05)
				(type default)
			)
			(fill no)
			(layer "B.CrtYd")
		)
		(fp_rect
			(start -0.5 0.25)
			(end 0.5 -0.25)
			(stroke
				(width 0.15)
				(type solid)
			)
			(fill no)
			(layer "B.Fab")
		)
		(pad "1" smd roundrect
			(at -0.48 0)
			(size 0.59 0.64)
			(layers "B.Cu" "B.Mask" "B.Paste")
			(roundrect_rratio 0.25)
			(net 506 "/FPGA Bank 16 & 17/GBE_RGMII.RXD0")
			(pintype "passive")
		)
		(pad "2" smd roundrect
			(at 0.48 0)
			(size 0.59 0.64)
			(layers "B.Cu" "B.Mask" "B.Paste")
			(roundrect_rratio 0.25)
			(net 1 "GND")
			(pintype "passive")
		)
	)
	(footprint "antmicro-footprints:C_0402_1005Metric"
		(layer "B.Cu")
		(at 202 116.5 180)
		(descr "Capacitor SMD 0402")
		(tags "capacitor SMD 0402")
		(property "Reference" "C61"
			(at -1.15 0.45 0)
			(layer "B.SilkS")
			(effects
				(font
					(size 0.7 0.7)
					(thickness 0.15)
				)
				(justify left bottom mirror)
			)
		)
		(property "Value" "C_100n_0402"
			(at 0 -1.169 0)
			(layer "B.Fab")
			(effects
				(font
					(size 0.7 0.7)
					(thickness 0.15)
				)
				(justify left bottom mirror)
			)
		)
		(property "Description" "SMD Multilayer Ceramic Capacitor, 0.1 µF, 50 V, 0402 [1005 Metric], ± 10%, X5R, GRM Series"
			(at 0 0 180)
			(layer "F.Fab")
			(hide yes)
			(effects
				(font
					(size 1.27 1.27)
					(thickness 0.15)
				)
			)
		)
		(property "Author" "Antmicro"
			(at 404 233 0)
			(layer "B.Fab")
			(hide yes)
			(effects
				(font
					(size 1 1)
					(thickness 0.15)
				)
				(justify mirror)
			)
		)
		(property "Dielectric" "X5R"
			(at 404 233 0)
			(layer "B.Fab")
			(hide yes)
			(effects
				(font
					(size 1 1)
					(thickness 0.15)
				)
				(justify mirror)
			)
		)
		(property "License" "Apache-2.0"
			(at 404 233 0)
			(layer "B.Fab")
			(hide yes)
			(effects
				(font
					(size 1 1)
					(thickness 0.15)
				)
				(justify mirror)
			)
		)
		(property "MPN" "GRM155R61H104KE14D"
			(at 404 233 0)
			(layer "B.Fab")
			(hide yes)
			(effects
				(font
					(size 1 1)
					(thickness 0.15)
				)
				(justify mirror)
			)
		)
		(property "Manufacturer" "Murata"
			(at 404 233 0)
			(layer "B.Fab")
			(hide yes)
			(effects
				(font
					(size 1 1)
					(thickness 0.15)
				)
				(justify mirror)
			)
		)
		(property "Val" "100n"
			(at 404 233 0)
			(layer "B.Fab")
			(hide yes)
			(effects
				(font
					(size 1 1)
					(thickness 0.15)
				)
				(justify mirror)
			)
		)
		(property "Voltage" "50V"
			(at 404 233 0)
			(layer "B.Fab")
			(hide yes)
			(effects
				(font
					(size 1 1)
					(thickness 0.15)
				)
				(justify mirror)
			)
		)
		(sheetname "FPGA Bank 16 & 17")
		(sheetfile "fpga-bank-16-17.kicad_sch")
		(attr smd)
		(fp_rect
			(start -0.925 0.47)
			(end 0.925 -0.47)
			(stroke
				(width 0.05)
				(type default)
			)
			(fill no)
			(layer "B.CrtYd")
		)
		(fp_line
			(start 0.504 0.25)
			(end 0.504 -0.248)
			(stroke
				(width 0.15)
				(type solid)
			)
			(layer "B.Fab")
		)
		(fp_line
			(start 0.504 -0.248)
			(end -0.494 -0.248)
			(stroke
				(width 0.15)
				(type solid)
			)
			(layer "B.Fab")
		)
		(fp_line
			(start -0.494 0.25)
			(end 0.504 0.25)
			(stroke
				(width 0.15)
				(type solid)
			)
			(layer "B.Fab")
		)
		(fp_line
			(start -0.494 -0.248)
			(end -0.494 0.25)
			(stroke
				(width 0.15)
				(type solid)
			)
			(layer "B.Fab")
		)
		(pad "1" smd roundrect
			(at -0.48 0 180)
			(size 0.59 0.64)
			(layers "B.Cu" "B.Mask" "B.Paste")
			(roundrect_rratio 0.25)
			(net 1 "GND")
			(pintype "passive")
		)
		(pad "2" smd roundrect
			(at 0.48 0 180)
			(size 0.59 0.64)
			(layers "B.Cu" "B.Mask" "B.Paste")
			(roundrect_rratio 0.25)
			(net 24 "+3V3")
			(pintype "passive")
		)
	)
	(footprint "antmicro-footprints:R_0402_1005Metric"
		(layer "B.Cu")
		(at 261.5 83.8)
		(descr "Resistor SMD 0402")
		(tags "resistor SMD 0402")
		(property "Reference" "R107"
			(at 1.425 1.275 180)
			(layer "B.SilkS")
			(effects
				(font
					(size 0.7 0.7)
					(thickness 0.15)
				)
				(justify left bottom mirror)
			)
		)
		(property "Value" "R_1k_0402"
			(at 0 -1.4 180)
			(layer "B.Fab")
			(effects
				(font
					(size 0.7 0.7)
					(thickness 0.15)
				)
				(justify left bottom mirror)
			)
		)
		(property "Description" "SMD Chip Resistor, 1 kohm, ± 1%, 63 mW, 0402 [1005 Metric], Thick Film, General Purpose"
			(at 0 0 0)
			(layer "F.Fab")
			(hide yes)
			(effects
				(font
					(size 1.27 1.27)
					(thickness 0.15)
				)
			)
		)
		(property "Author" "Antmicro"
			(at 0 0 0)
			(layer "B.Fab")
			(hide yes)
			(effects
				(font
					(size 1 1)
					(thickness 0.15)
				)
				(justify mirror)
			)
		)
		(property "License" "Apache-2.0"
			(at 0 0 0)
			(layer "B.Fab")
			(hide yes)
			(effects
				(font
					(size 1 1)
					(thickness 0.15)
				)
				(justify mirror)
			)
		)
		(property "MPN" "CR0402-FX-1001GLF"
			(at 0 0 0)
			(layer "B.Fab")
			(hide yes)
			(effects
				(font
					(size 1 1)
					(thickness 0.15)
				)
				(justify mirror)
			)
		)
		(property "Manufacturer" "Bourns"
			(at 0 0 0)
			(layer "B.Fab")
			(hide yes)
			(effects
				(font
					(size 1 1)
					(thickness 0.15)
				)
				(justify mirror)
			)
		)
		(property "Tolerance" "1%"
			(at 0 0 0)
			(layer "B.Fab")
			(hide yes)
			(effects
				(font
					(size 1 1)
					(thickness 0.15)
				)
				(justify mirror)
			)
		)
		(property "Val" "1k"
			(at 0 0 0)
			(layer "B.Fab")
			(hide yes)
			(effects
				(font
					(size 1 1)
					(thickness 0.15)
				)
				(justify mirror)
			)
		)
		(sheetname "User GPIO + LED + button + DIP switch")
		(sheetfile "user-gpio.kicad_sch")
		(attr smd)
		(fp_rect
			(start -0.925 0.47)
			(end 0.925 -0.47)
			(stroke
				(width 0.05)
				(type default)
			)
			(fill no)
			(layer "B.CrtYd")
		)
		(fp_rect
			(start -0.5 0.25)
			(end 0.5 -0.25)
			(stroke
				(width 0.15)
				(type solid)
			)
			(fill no)
			(layer "B.Fab")
		)
		(pad "1" smd roundrect
			(at -0.48 0)
			(size 0.59 0.64)
			(layers "B.Cu" "B.Mask" "B.Paste")
			(roundrect_rratio 0.25)
			(net 24 "+3V3")
			(pintype "passive")
		)
		(pad "2" smd roundrect
			(at 0.48 0)
			(size 0.59 0.64)
			(layers "B.Cu" "B.Mask" "B.Paste")
			(roundrect_rratio 0.25)
			(net 775 "Net-(D18-A)")
			(pintype "passive")
		)
	)
	(footprint "antmicro-footprints:R_0402_1005Metric"
		(layer "B.Cu")
		(at 200.891252 99.25 -90)
		(descr "Resistor SMD 0402")
		(tags "resistor SMD 0402")
		(property "Reference" "R208"
			(at 3.8 -0.333748 90)
			(layer "B.SilkS")
			(effects
				(font
					(size 0.7 0.7)
					(thickness 0.15)
				)
				(justify left bottom mirror)
			)
		)
		(property "Value" "R_10k_0402"
			(at 0 -1.4 90)
			(layer "B.Fab")
			(effects
				(font
					(size 0.7 0.7)
					(thickness 0.15)
				)
				(justify left bottom mirror)
			)
		)
		(property "Description" "SMD Chip Resistor, 10 kohm, ± 1%, 62.5 mW, 0402 [1005 Metric], Thick Film, General Purpose"
			(at 0 0 270)
			(layer "F.Fab")
			(hide yes)
			(effects
				(font
					(size 1.27 1.27)
					(thickness 0.15)
				)
			)
		)
		(property "Author" "Antmicro"
			(at 101.641252 300.141252 0)
			(layer "B.Fab")
			(hide yes)
			(effects
				(font
					(size 1 1)
					(thickness 0.15)
				)
				(justify mirror)
			)
		)
		(property "License" "Apache-2.0"
			(at 101.641252 300.141252 0)
			(layer "B.Fab")
			(hide yes)
			(effects
				(font
					(size 1 1)
					(thickness 0.15)
				)
				(justify mirror)
			)
		)
		(property "MPN" "CR0402-FX-1002GLF"
			(at 101.641252 300.141252 0)
			(layer "B.Fab")
			(hide yes)
			(effects
				(font
					(size 1 1)
					(thickness 0.15)
				)
				(justify mirror)
			)
		)
		(property "Manufacturer" "Bourns"
			(at 101.641252 300.141252 0)
			(layer "B.Fab")
			(hide yes)
			(effects
				(font
					(size 1 1)
					(thickness 0.15)
				)
				(justify mirror)
			)
		)
		(property "Tolerance" "1%"
			(at 101.641252 300.141252 0)
			(layer "B.Fab")
			(hide yes)
			(effects
				(font
					(size 1 1)
					(thickness 0.15)
				)
				(justify mirror)
			)
		)
		(property "Val" "10k"
			(at 101.641252 300.141252 0)
			(layer "B.Fab")
			(hide yes)
			(effects
				(font
					(size 1 1)
					(thickness 0.15)
				)
				(justify mirror)
			)
		)
		(sheetname "HDMI + Ethernet")
		(sheetfile "hdmi-ethernet.kicad_sch")
		(attr smd)
		(fp_rect
			(start -0.925 0.47)
			(end 0.925 -0.47)
			(stroke
				(width 0.05)
				(type default)
			)
			(fill no)
			(layer "B.CrtYd")
		)
		(fp_rect
			(start -0.5 0.25)
			(end 0.5 -0.25)
			(stroke
				(width 0.15)
				(type solid)
			)
			(fill no)
			(layer "B.Fab")
		)
		(pad "1" smd roundrect
			(at -0.48 0 270)
			(size 0.59 0.64)
			(layers "B.Cu" "B.Mask" "B.Paste")
			(roundrect_rratio 0.25)
			(net 510 "/FPGA Bank 16 & 17/GBE_RGMII.REFCLK")
			(pintype "passive")
		)
		(pad "2" smd roundrect
			(at 0.48 0 270)
			(size 0.59 0.64)
			(layers "B.Cu" "B.Mask" "B.Paste")
			(roundrect_rratio 0.25)
			(net 24 "+3V3")
			(pintype "passive")
		)
	)
)
